(kicad_pcb
	(version 20221018)
	(generator pcbnew)
	(general
    (thickness 1.518)
  )
	(paper "A4")
	(title_block
    (title "Kria K26 Devboard")
    (date "2024-03-26")
    (rev "1.2.5")
    (comment 1 "www.antmicro.com")
    (comment 2 "Antmicro Ltd.")
		(comment 9 "footprints 259-265 of 660")
	)
	(layers
    (0 "F.Cu" mixed)
    (1 "In1.Cu" power)
    (2 "In2.Cu" mixed)
    (3 "In3.Cu" power)
    (4 "In4.Cu" mixed)
    (5 "In5.Cu" power)
    (6 "In6.Cu" mixed)
    (31 "B.Cu" power)
    (32 "B.Adhes" user "B.Adhesive")
    (33 "F.Adhes" user "F.Adhesive")
    (34 "B.Paste" user)
    (35 "F.Paste" user)
    (36 "B.SilkS" user "B.Silkscreen")
    (37 "F.SilkS" user "F.Silkscreen")
    (38 "B.Mask" user)
    (39 "F.Mask" user)
    (40 "Dwgs.User" user "User.Drawings")
    (41 "Cmts.User" user "User.Comments")
    (42 "Eco1.User" user "User.Eco1")
    (43 "Eco2.User" user "User.Eco2")
    (44 "Edge.Cuts" user)
    (45 "Margin" user)
    (46 "B.CrtYd" user "B.Courtyard")
    (47 "F.CrtYd" user "F.Courtyard")
    (48 "B.Fab" user)
    (49 "F.Fab" user)
  )
	(footprint "kria-k26-devboard-footprints:TSOT23-6" (layer "F.Cu")
    (at 178 133 90)
    (property "Author" "Antmicro")
    (property "License" "Apache-2.0")
    (property "MPN" "AP62301WU-7")
    (property "Manufacturer" "Diodes Incorporated")
    (property "Sheetfile" "dc-dc-conventers.kicad_sch")
    (property "Sheetname" "DC/DC conventers")
    (property "ki_description" "DC-DC Switching Synchronous Buck Regulator, Adjustable, 4.2V-18Vin, 0.8V-7V/3A out, TSOT-26-6")
    (property "ki_keywords" "SMT, PMIC, IC, VOLTAGE")
    (attr smd)
    (fp_text reference "U54" (at -1.84 -1.67 270) (layer "F.SilkS")
        (effects (font (size 0.7 0.7) (thickness 0.15)) (justify left bottom))
    )
    (fp_text value "AP62301_TSOT" (at -0.005 2.6 90) (layer "F.Fab") hide
        (effects (font (size 0.7 0.7) (thickness 0.15)) (justify left bottom))
    )
    (fp_text user "${REFERENCE}" (at -1.893 6.168 90) (layer "F.Fab") hide
        (effects (font (size 0.7 0.7) (thickness 0.15)) (justify left bottom))
    )
    (fp_text user "License: Apache-2.0" (at -1.893 4.967 90) (layer "F.Fab") hide
        (effects (font (size 0.7 0.7) (thickness 0.15)) (justify left bottom))
    )
    (fp_text user "Author: Antmicro" (at -1.893 7.368 90) (layer "F.Fab") hide
        (effects (font (size 0.7 0.7) (thickness 0.15)) (justify left bottom))
    )
    (fp_line (start -1.4805 0.725) (end -1.4795 -0.725)
      (stroke (width 0.15) (type solid)) (layer "F.SilkS"))
    (fp_line (start -1.4805 0.725) (end -1.3905 0.725)
      (stroke (width 0.15) (type solid)) (layer "F.SilkS"))
    (fp_line (start -1.4795 -0.725) (end -1.3905 -0.725)
      (stroke (width 0.15) (type solid)) (layer "F.SilkS"))
    (fp_line (start 1.479 0.73) (end 1.38 0.73)
      (stroke (width 0.15) (type solid)) (layer "F.SilkS"))
    (fp_line (start 1.48 -0.72) (end 1.38 -0.72)
      (stroke (width 0.15) (type solid)) (layer "F.SilkS"))
    (fp_line (start 1.48 -0.72) (end 1.479 0.73)
      (stroke (width 0.15) (type solid)) (layer "F.SilkS"))
    (fp_circle (center -1.499 1.236) (end -1.45 1.236)
      (stroke (width 0.15) (type solid)) (fill solid) (layer "F.SilkS"))
    (fp_rect (start -1.65 -1.61) (end 1.65 1.61)
      (stroke (width 0.05) (type solid)) (fill none) (layer "F.CrtYd"))
    (fp_line (start -1.527 -0.833) (end 1.523 -0.833)
      (stroke (width 0.15) (type solid)) (layer "F.Fab"))
    (fp_line (start -1.527 0.491) (end -1.527 -0.833)
      (stroke (width 0.15) (type solid)) (layer "F.Fab"))
    (fp_line (start -1.527 0.491) (end -1.102 0.916)
      (stroke (width 0.15) (type solid)) (layer "F.Fab"))
    (fp_line (start -1.102 0.916) (end 1.523 0.916)
      (stroke (width 0.15) (type solid)) (layer "F.Fab"))
    (fp_line (start 1.523 -0.833) (end 1.523 0.916)
      (stroke (width 0.15) (type solid)) (layer "F.Fab"))
    (pad "1" smd rect (at -0.952 1.18 90) (size 0.7 0.8) (layers "F.Cu" "F.Paste" "F.Mask")
      (net 1 "GND") (pinfunction "GND") (pintype "power_in"))
    (pad "2" smd rect (at -0.001 1.18 90) (size 0.7 0.8) (layers "F.Cu" "F.Paste" "F.Mask")
      (net 315 "/Power Supply/DC/DC conventers/SW_PL_3V3") (pinfunction "SW") (pintype "power_out"))
    (pad "3" smd rect (at 0.947 1.18 90) (size 0.7 0.8) (layers "F.Cu" "F.Paste" "F.Mask")
      (net 14 "/Power Supply/DC/DC conventers/DC_MAIN_BUS") (pinfunction "VIN") (pintype "power_in"))
    (pad "4" smd rect (at 0.947 -1.18 90) (size 0.7 0.8) (layers "F.Cu" "F.Paste" "F.Mask")
      (net 693 "Net-(U54-FB)") (pinfunction "FB") (pintype "input"))
    (pad "5" smd rect (at -0.001 -1.18 90) (size 0.7 0.8) (layers "F.Cu" "F.Paste" "F.Mask")
      (net 24 "/Power Supply/VCCOEN_PL_M2C") (pinfunction "EN") (pintype "input"))
    (pad "6" smd rect (at -0.952 -1.18 90) (size 0.7 0.8) (layers "F.Cu" "F.Paste" "F.Mask")
      (net 325 "Net-(U54-BST)") (pinfunction "BST") (pintype "output"))
  )
	(footprint "kria-k26-devboard-footprints:C_0402_1005Metric" (layer "F.Cu")
    (at 148.3 93.83 -90)
    (descr "Capacitor SMD 0402")
    (tags "capacitor SMD 0402")
    (property "Author" "Antmicro")
    (property "Dielectric" "X5R")
    (property "License" "Apache-2.0")
    (property "MPN" "GRM155R61H104KE14D")
    (property "Manufacturer" "Murata")
    (property "Sheetfile" "eth.kicad_sch")
    (property "Sheetname" "Ethernet")
    (property "Val" "100n")
    (property "Voltage" "50V")
    (property "ki_description" " ")
    (attr smd)
    (fp_text reference "C100" (at 3.69 -0.41 -90) (layer "F.SilkS")
        (effects (font (size 0.7 0.7) (thickness 0.15)) (justify left bottom))
    )
    (fp_text value "C_100n_0402" (at 0 1.4 -90) (layer "F.Fab") hide
        (effects (font (size 0.7 0.7) (thickness 0.15)) (justify left bottom))
    )
    (fp_text user "License: Apache-2.0" (at -0.932 5.17 -90) (layer "F.Fab") hide
        (effects (font (size 0.7 0.7) (thickness 0.15)) (justify left bottom))
    )
    (fp_text user "${REFERENCE}" (at -0.932 3.168 -90) (layer "F.Fab") hide
        (effects (font (size 0.7 0.7) (thickness 0.15)) (justify left bottom))
    )
    (fp_text user "Author: Antmicro" (at -0.932 4.17 -90) (layer "F.Fab") hide
        (effects (font (size 0.7 0.7) (thickness 0.15)) (justify left bottom))
    )
    (fp_rect (start -0.94 -0.47) (end 0.94 0.47)
      (stroke (width 0.05) (type solid)) (fill none) (layer "F.CrtYd"))
    (fp_rect (start -0.499 -0.249) (end 0.499 0.249)
      (stroke (width 0.15) (type solid)) (fill none) (layer "F.Fab"))
    (pad "1" smd roundrect (at -0.484 0 270) (size 0.59 0.64) (layers "F.Cu" "F.Paste" "F.Mask") (roundrect_rratio 0.25)
      (net 17 "PS_1V8") (pintype "passive"))
    (pad "2" smd roundrect (at 0.484 0 270) (size 0.59 0.64) (layers "F.Cu" "F.Paste" "F.Mask") (roundrect_rratio 0.25)
      (net 1 "GND") (pintype "passive"))
  )
	(footprint "kria-k26-devboard-footprints:R_0402_1005Metric" (layer "F.Cu")
    (at 147.925 73.9 90)
    (descr "Resistor SMD 0402")
    (tags "resistor SMD 0402")
    (property "Author" "Antmicro")
    (property "License" "Apache-2.0")
    (property "MPN" "CR0402-FX-1003GLF")
    (property "Manufacturer" "Bourns")
    (property "Sheetfile" "dc-dc-conventers.kicad_sch")
    (property "Sheetname" "DC/DC conventers")
    (property "Tolerance" "1%")
    (property "Val" "100k")
    (property "ki_description" "100k resistor in 0402 package with 1% tolerance")
    (attr smd)
    (fp_text reference "R118" (at -1.27 -0.635 90) (layer "F.SilkS")
        (effects (font (size 0.7 0.7) (thickness 0.15)) (justify left bottom))
    )
    (fp_text value "R_100k_0402" (at 0 1.4 90) (layer "F.Fab") hide
        (effects (font (size 0.7 0.7) (thickness 0.15)) (justify left bottom))
    )
    (fp_text user "${REFERENCE}" (at -0.95 3.168 90) (layer "F.Fab") hide
        (effects (font (size 0.7 0.7) (thickness 0.15)) (justify left bottom))
    )
    (fp_text user "License: Apache-2.0" (at -0.95 5.169 90) (layer "F.Fab") hide
        (effects (font (size 0.7 0.7) (thickness 0.15)) (justify left bottom))
    )
    (fp_text user "Author: Antmicro" (at -0.95 4.169 90) (layer "F.Fab") hide
        (effects (font (size 0.7 0.7) (thickness 0.15)) (justify left bottom))
    )
    (fp_rect (start -0.93 -0.47) (end 0.93 0.47)
      (stroke (width 0.05) (type solid)) (fill none) (layer "F.CrtYd"))
    (fp_rect (start -0.5 -0.25) (end 0.5 0.25)
      (stroke (width 0.15) (type solid)) (fill none) (layer "F.Fab"))
    (pad "1" smd roundrect (at -0.485 0 90) (size 0.59 0.64) (layers "F.Cu" "F.Paste" "F.Mask") (roundrect_rratio 0.25)
      (net 685 "Net-(U47-EN)") (pintype "passive"))
    (pad "2" smd roundrect (at 0.485 0 90) (size 0.59 0.64) (layers "F.Cu" "F.Paste" "F.Mask") (roundrect_rratio 0.25)
      (net 14 "/Power Supply/DC/DC conventers/DC_MAIN_BUS") (pintype "passive"))
  )
	(footprint "kria-k26-devboard-footprints:LED_0603_1608Metric_G" (layer "F.Cu")
    (at 150.575 76.9)
    (descr "LED SMD 0603 Green")
    (tags "LED SMD 0603 Green")
    (property "Author" "Antmicro")
    (property "Color" "Green")
    (property "License" "Apache-2.0")
    (property "MPN" "LG L29K-G2J1-24-Z")
    (property "Manufacturer" "OSRAM")
    (property "Sheetfile" "dc-dc-conventers.kicad_sch")
    (property "Sheetname" "DC/DC conventers")
    (property "ki_description" "LED, Green, SMT, 0603, 20 mA, 2.1 V, 570 nm")
    (property "ki_keywords" "0603, SMT, DIODE, SEMICONDUCTOR, UNICOLOR")
    (attr smd)
    (fp_text reference "D13" (at -0.995 1.53) (layer "F.SilkS")
        (effects (font (size 0.7 0.7) (thickness 0.15)) (justify left bottom))
    )
    (fp_text value "LED_G_0603_LG_L29K-G2J1-24-Z" (at 0 1.6) (layer "F.Fab") hide
        (effects (font (size 0.7 0.7) (thickness 0.15)) (justify left bottom))
    )
    (fp_text user "Author: Antmicro" (at -1.31 4.769) (layer "F.Fab") hide
        (effects (font (size 0.7 0.7) (thickness 0.15)) (justify left bottom))
    )
    (fp_text user "${REFERENCE}" (at -1.31 3.769) (layer "F.Fab") hide
        (effects (font (size 0.7 0.7) (thickness 0.15)) (justify left bottom))
    )
    (fp_text user "License: Apache-2.0" (at -1.31 5.769) (layer "F.Fab") hide
        (effects (font (size 0.7 0.7) (thickness 0.15)) (justify left bottom))
    )
    (fp_line (start -0.27 -0.35) (end 0.27 -0.35)
      (stroke (width 0.15) (type solid)) (layer "F.SilkS"))
    (fp_line (start -0.27 0.351) (end 0.27 0.351)
      (stroke (width 0.15) (type solid)) (layer "F.SilkS"))
    (fp_line (start -0.106328 -0.200008) (end -0.106328 0.199992)
      (stroke (width 0.1) (type solid)) (layer "F.SilkS"))
    (fp_line (start -0.106328 -0.200008) (end 0.093672 -0.000008)
      (stroke (width 0.1) (type solid)) (layer "F.SilkS"))
    (fp_line (start -0.106328 -0.000008) (end -0.29 0)
      (stroke (width 0.1) (type solid)) (layer "F.SilkS"))
    (fp_line (start 0.093672 -0.200008) (end 0.093672 0.199992)
      (stroke (width 0.1) (type solid)) (layer "F.SilkS"))
    (fp_line (start 0.093672 -0.000008) (end -0.106328 0.199992)
      (stroke (width 0.1) (type solid)) (layer "F.SilkS"))
    (fp_line (start 0.093672 -0.000008) (end 0.293672 -0.000008)
      (stroke (width 0.1) (type solid)) (layer "F.SilkS"))
    (fp_line (start 1.25 0.32) (end 1.25 -0.32)
      (stroke (width 0.15) (type solid)) (layer "F.SilkS"))
    (fp_rect (start 1.26 0.65) (end -1.26 -0.65)
      (stroke (width 0.05) (type solid)) (fill none) (layer "F.CrtYd"))
    (fp_line (start -0.599 0) (end -0.201 0)
      (stroke (width 0.15) (type solid)) (layer "F.Fab"))
    (fp_line (start -0.201 -0.2) (end -0.201 0)
      (stroke (width 0.15) (type solid)) (layer "F.Fab"))
    (fp_line (start -0.201 0) (end -0.201 0.202)
      (stroke (width 0.15) (type solid)) (layer "F.Fab"))
    (fp_line (start -0.201 0.202) (end 0.101 0)
      (stroke (width 0.15) (type solid)) (layer "F.Fab"))
    (fp_line (start 0.101 0) (end -0.201 -0.2)
      (stroke (width 0.15) (type solid)) (layer "F.Fab"))
    (fp_line (start 0.199 -0.2) (end 0.199 -0.1)
      (stroke (width 0.15) (type solid)) (layer "F.Fab"))
    (fp_line (start 0.199 0) (end 0.597 0)
      (stroke (width 0.15) (type solid)) (layer "F.Fab"))
    (fp_line (start 0.199 0.202) (end 0.199 -0.1)
      (stroke (width 0.15) (type solid)) (layer "F.Fab"))
    (fp_rect (start -0.848 -0.4) (end 0.85 0.402)
      (stroke (width 0.15) (type solid)) (fill none) (layer "F.Fab"))
    (pad "1" smd rect (at -0.75 0 180) (size 0.8 0.8) (layers "F.Cu" "F.Paste" "F.Mask")
      (net 330 "Net-(D13-Pad1)") (pintype "passive"))
    (pad "2" smd rect (at 0.75 0 180) (size 0.8 0.8) (layers "F.Cu" "F.Paste" "F.Mask")
      (net 1 "GND") (pinfunction "2") (pintype "passive"))
  )
	(footprint "kria-k26-devboard-footprints:R_0402_1005Metric" (layer "F.Cu")
    (at 148.625 77.35 -90)
    (descr "Resistor SMD 0402")
    (tags "resistor SMD 0402")
    (property "Author" "Antmicro")
    (property "License" "Apache-2.0")
    (property "MPN" "CR0402-FX-2201GLF")
    (property "Manufacturer" "Bourns")
    (property "Sheetfile" "dc-dc-conventers.kicad_sch")
    (property "Sheetname" "DC/DC conventers")
    (property "Tolerance" "1%")
    (property "Val" "2k2")
    (property "ki_description" "2k2 resistor in 0402 package with 1% tolerance")
    (attr smd)
    (fp_text reference "R121" (at 1.31 0.615 -90) (layer "F.SilkS")
        (effects (font (size 0.7 0.7) (thickness 0.15)) (justify left bottom))
    )
    (fp_text value "R_2k2_0402" (at 0 1.4 -90) (layer "F.Fab") hide
        (effects (font (size 0.7 0.7) (thickness 0.15)) (justify left bottom))
    )
    (fp_text user "${REFERENCE}" (at -0.95 3.168 -90) (layer "F.Fab") hide
        (effects (font (size 0.7 0.7) (thickness 0.15)) (justify left bottom))
    )
    (fp_text user "Author: Antmicro" (at -0.95 4.169 -90) (layer "F.Fab") hide
        (effects (font (size 0.7 0.7) (thickness 0.15)) (justify left bottom))
    )
    (fp_text user "License: Apache-2.0" (at -0.95 5.169 -90) (layer "F.Fab") hide
        (effects (font (size 0.7 0.7) (thickness 0.15)) (justify left bottom))
    )
    (fp_rect (start -0.93 -0.47) (end 0.93 0.47)
      (stroke (width 0.05) (type solid)) (fill none) (layer "F.CrtYd"))
    (fp_rect (start -0.5 -0.25) (end 0.5 0.25)
      (stroke (width 0.15) (type solid)) (fill none) (layer "F.Fab"))
    (pad "1" smd roundrect (at -0.485 0 270) (size 0.59 0.64) (layers "F.Cu" "F.Paste" "F.Mask") (roundrect_rratio 0.25)
      (net 330 "Net-(D13-Pad1)") (pintype "passive"))
    (pad "2" smd roundrect (at 0.485 0 270) (size 0.59 0.64) (layers "F.Cu" "F.Paste" "F.Mask") (roundrect_rratio 0.25)
      (net 772 "/Power Supply/DC/DC conventers/USB_5V_OUT") (pintype "passive"))
  )
	(footprint "kria-k26-devboard-footprints:Spacer_Drill4.45mm_H5mm_9774050960R" (layer "F.Cu")
    (at 89.556999 144.4435 180)
    (property "Author" "Antmicro")
    (property "License" "Apache-2.0")
    (property "MPN" "9774050960R")
    (property "Manufacturer" "Würth Elektronik")
    (property "Sheetfile" "k26_som.kicad_sch")
    (property "Sheetname" "Xilinx K26 SOM")
    (property "ki_description" "Spacer, SMT, Non Stop, Steel, Swage Round, 6 mm x 5 mm, 3.3 mm Internal, WA-SMST Series")
    (property "ki_keywords" "SPACER")
    (clearance 0.6)
    (attr smd)
    (fp_text reference "SP1" (at 0 -3.4 180) (layer "F.SilkS")
        (effects (font (size 0.7 0.7) (thickness 0.15)) (justify left bottom))
    )
    (fp_text value "Spacer_Drill4.45mm_H5mm_9774050960R" (at 0 4.2 180) (layer "F.Fab")
        (effects (font (size 0.7 0.7) (thickness 0.15)) (justify left bottom))
    )
    (fp_text user "Author: Antmicro" (at -3.25 8.6 180) (layer "F.Fab") hide
        (effects (font (size 0.7 0.7) (thickness 0.15)) (justify left bottom))
    )
    (fp_text user "License: Apache-2.0" (at -3.25 6.2 180) (layer "F.Fab") hide
        (effects (font (size 0.7 0.7) (thickness 0.15)) (justify left bottom))
    )
    (fp_text user "${REFERENCE}" (at -3.25 7.4 180) (layer "F.Fab") hide
        (effects (font (size 0.7 0.7) (thickness 0.15)) (justify left bottom))
    )
    (fp_circle (center 0 0) (end 3.25 0)
      (stroke (width 0.05) (type solid)) (fill none) (layer "F.CrtYd"))
    (fp_circle (center 0 0) (end 2.564 0)
      (stroke (width 0.15) (type solid)) (fill none) (layer "F.Fab"))
    (pad "1" thru_hole circle (at 0 0 180) (size 6 6) (drill 4.45) (layers "*.Cu" "*.Mask" "F.Paste")
      (net 1 "GND") (pintype "passive") (solder_paste_margin_ratio -0.05))
  )
	(footprint "kria-k26-devboard-footprints:TP_SMD_0.75mm" (layer "F.Cu")
    (at 103.55 137.5)
    (property "Author" "Antmicro")
    (property "License" "Apache-2.0")
    (property "MPN" "")
    (property "Manufacturer" "")
    (property "Sheetfile" "debug.kicad_sch")
    (property "Sheetname" "Debug and JTAG")
    (property "ki_description" "Test Point 0.75mm")
    (attr exclude_from_pos_files)
    (fp_text reference "TP33" (at -3.02 0.39) (layer "F.SilkS")
        (effects (font (size 0.7 0.7) (thickness 0.15)) (justify left bottom))
    )
    (fp_text value "TP_0.75mm_SMD" (at 0 1.2) (layer "F.Fab") hide
        (effects (font (size 0.7 0.7) (thickness 0.15)) (justify left bottom))
    )
    (fp_text user "License: Apache-2.0" (at -0.4 5.101) (layer "F.Fab") hide
        (effects (font (size 0.7 0.7) (thickness 0.15)) (justify left bottom))
    )
    (fp_text user "Author: Antmicro" (at -0.4 3.901) (layer "F.Fab") hide
        (effects (font (size 0.7 0.7) (thickness 0.15)) (justify left bottom))
    )
    (fp_text user "${REFERENCE}" (at -0.4 2.7) (layer "F.Fab") hide
        (effects (font (size 0.7 0.7) (thickness 0.15)) (justify left bottom))
    )
    (pad "1" smd circle (at 0 0) (size 0.75 0.75) (layers "F.Cu" "F.Mask")
      (net 186 "/Debug and JTAG/~{EEPROM_WC}") (pinfunction "1") (pintype "passive"))
  )
)
